(kicad_pcb
	(version 20260206)
	(generator "pcbnew")
	(generator_version "10.0")
	(general
		(thickness 1.6)
		(legacy_teardrops no)
	)
	(paper "A4")
	(title_block
		(title "Bryce Canyon_F.DPB_16315-1-OCP.brd")
		(comment 1 "Bryce Canyon / footprints 972-978 of 2223")
	)
	(layers
		(0 "F.Cu" signal "TOP")
		(4 "In1.Cu" signal "L2GND")
		(6 "In2.Cu" signal "L3")
		(8 "In3.Cu" signal "L4GND")
		(10 "In4.Cu" signal "L5")
		(12 "In5.Cu" signal "L6VCC")
		(14 "In6.Cu" signal "L7VCC")
		(16 "In7.Cu" signal "L8")
		(18 "In8.Cu" signal "L9GND")
		(20 "In9.Cu" signal "L10")
		(22 "In10.Cu" signal "L11GND")
		(2 "B.Cu" signal "BOTTOM")
		(9 "F.Adhes" user "F.Adhesive")
		(11 "B.Adhes" user "B.Adhesive")
		(13 "F.Paste" user "Package Geometry/Pastemask Top")
		(15 "B.Paste" user "Package Geometry/Pastemask Bottom")
		(5 "F.SilkS" user "Ref Des/Silkscreen Top")
		(7 "B.SilkS" user "Ref Des/Silkscreen Bottom")
		(1 "F.Mask" user "Board Geometry/Soldermask Top")
		(3 "B.Mask" user "Board Geometry/Soldermask Bottom")
		(17 "Dwgs.User" user "User.Drawings")
		(19 "Cmts.User" user "User.Comments")
		(21 "Eco1.User" user "User.Eco1")
		(23 "Eco2.User" user "User.Eco2")
		(25 "Edge.Cuts" user "Board Geometry/Outline")
		(27 "Margin" user)
		(31 "F.CrtYd" user "Package Geometry/Place Bound Top")
		(29 "B.CrtYd" user "Package Geometry/Place Bound Bottom")
		(35 "F.Fab" user "Ref Des/Assembly Top")
		(33 "B.Fab" user "Ref Des/Assembly Bottom")
	)
	(footprint ""
		(layer "F.Cu")
		(at 155.803854 -28.531566 -90)
		(property "Reference" "R378"
			(at 0 0 270)
			(layer "F.SilkS")
			(hide yes)
			(effects
				(font
					(size 1.27 1.27)
				)
			)
		)
		(property "Value" "100KR2F-L1-GP"
			(at 0.064008 -3.993896 270)
			(unlocked yes)
			(layer "F.Fab")
			(hide yes)
			(effects
				(font
					(size 1.016 1.016)
					(thickness 0.1524)
				)
			)
		)
		(property "Device Type" "R402H16"
			(at 0.064008 -5.517896 270)
			(unlocked yes)
			(layer "F.Fab")
			(hide yes)
			(effects
				(font
					(size 1.016 1.016)
					(thickness 0.1524)
				)
			)
		)
		(duplicate_pad_numbers_are_jumpers no)
		(fp_line
			(start -0.508 -0.9398)
			(end -0.508 0.9398)
			(stroke
				(width 0.1524)
				(type default)
			)
			(layer "F.SilkS")
		)
		(fp_line
			(start 0.508 -0.9398)
			(end -0.508 -0.9398)
			(stroke
				(width 0.1524)
				(type default)
			)
			(layer "F.SilkS")
		)
		(fp_rect
			(start -0.508 0.9398)
			(end 0.508 -0.9398)
			(stroke
				(width 0)
				(type default)
			)
			(fill no)
			(layer "F.CrtYd")
		)
		(fp_rect
			(start -0.508 0.9398)
			(end 0.508 -0.9398)
			(stroke
				(width 0)
				(type default)
			)
			(fill no)
			(layer "F.Fab")
		)
		(pad "1" smd custom
			(at 0 -0.4445 270)
			(size 0.1397 0.1397)
			(layers "F.Cu" "F.Mask" "F.Paste")
			(net "P3V3_STBY_A")
			(options
				(clearance outline)
				(anchor circle)
			)
			(primitives
				(gr_poly
					(pts
						(arc
							(start -0.1778 -0.2794)
							(mid -0.249642 -0.249642)
							(end -0.2794 -0.1778)
						)
						(arc
							(start -0.2794 0.1778)
							(mid -0.249642 0.249642)
							(end -0.1778 0.2794)
						)
						(arc
							(start 0.1778 0.2794)
							(mid 0.249642 0.249642)
							(end 0.2794 0.1778)
						)
						(arc
							(start 0.2794 -0.1778)
							(mid 0.249642 -0.249642)
							(end 0.1778 -0.2794)
						)
					)
					(width 0)
					(fill yes)
				)
			)
		)
		(pad "2" smd custom
			(at 0 0.4445 270)
			(size 0.1397 0.1397)
			(layers "F.Cu" "F.Mask" "F.Paste")
			(net "IOM_A_INS_N")
			(options
				(clearance outline)
				(anchor circle)
			)
			(primitives
				(gr_poly
					(pts
						(arc
							(start -0.1778 -0.2794)
							(mid -0.249642 -0.249642)
							(end -0.2794 -0.1778)
						)
						(arc
							(start -0.2794 0.1778)
							(mid -0.249642 0.249642)
							(end -0.1778 0.2794)
						)
						(arc
							(start 0.1778 0.2794)
							(mid 0.249642 0.249642)
							(end 0.2794 0.1778)
						)
						(arc
							(start 0.2794 -0.1778)
							(mid 0.249642 -0.249642)
							(end 0.1778 -0.2794)
						)
					)
					(width 0)
					(fill yes)
				)
			)
		)
	)
	(footprint ""
		(layer "F.Cu")
		(at 86.832948 -292.270942)
		(property "Reference" "R175"
			(at 0 0 0)
			(layer "F.SilkS")
			(hide yes)
			(effects
				(font
					(size 1.27 1.27)
				)
			)
		)
		(property "Value" "2R6F-GP"
			(at -0.0508 -4.8514 0)
			(unlocked yes)
			(layer "F.Fab")
			(hide yes)
			(effects
				(font
					(size 1.016 1.016)
					(thickness 0.1524)
				)
			)
		)
		(property "Device Type" "R1206H26"
			(at 0 -6.3754 0)
			(unlocked yes)
			(layer "F.Fab")
			(hide yes)
			(effects
				(font
					(size 1.016 1.016)
					(thickness 0.1524)
				)
			)
		)
		(duplicate_pad_numbers_are_jumpers no)
		(fp_line
			(start -1.016 -2.2352)
			(end 1.016 -2.2352)
			(stroke
				(width 0.1524)
				(type default)
			)
			(layer "F.SilkS")
		)
		(fp_line
			(start -1.016 2.2352)
			(end -1.016 -2.2352)
			(stroke
				(width 0.1524)
				(type default)
			)
			(layer "F.SilkS")
		)
		(fp_line
			(start 1.016 -2.2352)
			(end 1.016 2.2352)
			(stroke
				(width 0.1524)
				(type default)
			)
			(layer "F.SilkS")
		)
		(fp_line
			(start 1.016 2.2352)
			(end -1.016 2.2352)
			(stroke
				(width 0.1524)
				(type default)
			)
			(layer "F.SilkS")
		)
		(fp_rect
			(start -1.0922 2.3114)
			(end 1.0922 -2.3114)
			(stroke
				(width 0)
				(type default)
			)
			(fill no)
			(layer "F.CrtYd")
		)
		(fp_poly
			(pts
				(xy -1.0922 -2.3114) (xy 1.0922 -2.3114) (xy 1.0922 2.3114) (xy -1.0922 2.3114)
			)
			(stroke
				(width 0)
				(type default)
			)
			(fill no)
			(layer "F.Fab")
		)
		(pad "1" smd rect
			(at 0 -1.397)
			(size 1.651 1.27)
			(layers "F.Cu" "F.Mask" "F.Paste")
			(net "P5V_HDD2")
		)
		(pad "2" smd rect
			(at 0 1.397)
			(size 1.651 1.27)
			(layers "F.Cu" "F.Mask" "F.Paste")
			(net "5V_PRE_2")
		)
	)
	(footprint ""
		(layer "F.Cu")
		(at 464.9089 -171.809918 -90)
		(property "Reference" "R651"
			(at 0 0 270)
			(layer "F.SilkS")
			(hide yes)
			(effects
				(font
					(size 1.27 1.27)
				)
			)
		)
		(property "Value" "300KR2F-GP"
			(at 0.064008 -3.993896 270)
			(unlocked yes)
			(layer "F.Fab")
			(hide yes)
			(effects
				(font
					(size 1.016 1.016)
					(thickness 0.1524)
				)
			)
		)
		(property "Device Type" "R402H16"
			(at 0.064008 -5.517896 270)
			(unlocked yes)
			(layer "F.Fab")
			(hide yes)
			(effects
				(font
					(size 1.016 1.016)
					(thickness 0.1524)
				)
			)
		)
		(duplicate_pad_numbers_are_jumpers no)
		(fp_line
			(start -0.508 -0.9398)
			(end -0.508 0.9398)
			(stroke
				(width 0.1524)
				(type default)
			)
			(layer "F.SilkS")
		)
		(fp_line
			(start 0.508 -0.9398)
			(end -0.508 -0.9398)
			(stroke
				(width 0.1524)
				(type default)
			)
			(layer "F.SilkS")
		)
		(fp_rect
			(start -0.508 0.9398)
			(end 0.508 -0.9398)
			(stroke
				(width 0)
				(type default)
			)
			(fill no)
			(layer "F.CrtYd")
		)
		(fp_rect
			(start -0.508 0.9398)
			(end 0.508 -0.9398)
			(stroke
				(width 0)
				(type default)
			)
			(fill no)
			(layer "F.Fab")
		)
		(pad "1" smd custom
			(at 0 -0.4445 270)
			(size 0.1397 0.1397)
			(layers "F.Cu" "F.Mask" "F.Paste")
			(net "SW_HDD_N22")
			(options
				(clearance outline)
				(anchor circle)
			)
			(primitives
				(gr_poly
					(pts
						(arc
							(start -0.1778 -0.2794)
							(mid -0.249642 -0.249642)
							(end -0.2794 -0.1778)
						)
						(arc
							(start -0.2794 0.1778)
							(mid -0.249642 0.249642)
							(end -0.1778 0.2794)
						)
						(arc
							(start 0.1778 0.2794)
							(mid 0.249642 0.249642)
							(end 0.2794 0.1778)
						)
						(arc
							(start 0.2794 -0.1778)
							(mid 0.249642 -0.249642)
							(end 0.1778 -0.2794)
						)
					)
					(width 0)
					(fill yes)
				)
			)
		)
		(pad "2" smd custom
			(at 0 0.4445 270)
			(size 0.1397 0.1397)
			(layers "F.Cu" "F.Mask" "F.Paste")
			(net "P12V_A")
			(options
				(clearance outline)
				(anchor circle)
			)
			(primitives
				(gr_poly
					(pts
						(arc
							(start -0.1778 -0.2794)
							(mid -0.249642 -0.249642)
							(end -0.2794 -0.1778)
						)
						(arc
							(start -0.2794 0.1778)
							(mid -0.249642 0.249642)
							(end -0.1778 0.2794)
						)
						(arc
							(start 0.1778 0.2794)
							(mid 0.249642 0.249642)
							(end 0.2794 0.1778)
						)
						(arc
							(start 0.2794 -0.1778)
							(mid 0.249642 -0.249642)
							(end 0.1778 -0.2794)
						)
					)
					(width 0)
					(fill yes)
				)
			)
		)
	)
	(footprint ""
		(layer "F.Cu")
		(at 224.553526 -134.616698 -90)
		(property "Reference" "TP220"
			(at 0 0 270)
			(layer "F.SilkS")
			(hide yes)
			(effects
				(font
					(size 1.27 1.27)
				)
			)
		)
		(property "Value" "TPAD32-GP"
			(at -0.0508 -1.6764 270)
			(unlocked yes)
			(layer "F.Fab")
			(hide yes)
			(effects
				(font
					(size 1.016 1.016)
					(thickness 0.1524)
				)
			)
		)
		(property "Device Type" "TPAD32"
			(at -0.0508 -3.2004 270)
			(unlocked yes)
			(layer "F.Fab")
			(hide yes)
			(effects
				(font
					(size 1.016 1.016)
					(thickness 0.1524)
				)
			)
		)
		(duplicate_pad_numbers_are_jumpers no)
		(fp_poly
			(pts
				(arc
					(start 0 -0.4064)
					(mid 0 0.4064)
					(end 0 -0.4064)
				)
			)
			(stroke
				(width 0)
				(type default)
			)
			(fill no)
			(layer "F.CrtYd")
		)
		(fp_poly
			(pts
				(arc
					(start 0 -0.7112)
					(mid 0 0.7112)
					(end 0 -0.7112)
				)
			)
			(stroke
				(width 0)
				(type default)
			)
			(fill no)
			(layer "F.Fab")
		)
		(pad "1" smd circle
			(at 0 0 270)
			(size 0.8128 0.8128)
			(layers "F.Cu" "F.Mask" "F.Paste")
			(net "TP_PCIE_COMP_A_CLK_1_DN")
		)
	)
	(footprint ""
		(layer "F.Cu")
		(at 345.641676 -293.871396)
		(property "Reference" "Q258"
			(at 0 0 0)
			(layer "F.SilkS")
			(hide yes)
			(effects
				(font
					(size 1.27 1.27)
				)
			)
		)
		(property "Value" "2N7002K-2-GP"
			(at 0.127 -8.9662 0)
			(unlocked yes)
			(layer "F.Fab")
			(hide yes)
			(effects
				(font
					(size 1.016 1.016)
					(thickness 0.1524)
				)
			)
		)
		(property "Device Type" "SOT23DGS2D4H44"
			(at 0.127 -10.4902 0)
			(unlocked yes)
			(layer "F.Fab")
			(hide yes)
			(effects
				(font
					(size 1.016 1.016)
					(thickness 0.1524)
				)
			)
		)
		(duplicate_pad_numbers_are_jumpers no)
		(fp_line
			(start -1.651 -1.778)
			(end -1.651 1.778)
			(stroke
				(width 0.1524)
				(type default)
			)
			(layer "F.SilkS")
		)
		(fp_line
			(start -1.651 1.778)
			(end 1.651 1.778)
			(stroke
				(width 0.1524)
				(type default)
			)
			(layer "F.SilkS")
		)
		(fp_line
			(start 1.651 -1.778)
			(end -1.651 -1.778)
			(stroke
				(width 0.1524)
				(type default)
			)
			(layer "F.SilkS")
		)
		(fp_line
			(start 1.651 1.778)
			(end 1.651 -1.778)
			(stroke
				(width 0.1524)
				(type default)
			)
			(layer "F.SilkS")
		)
		(fp_poly
			(pts
				(xy -1.778 1.8796) (xy -1.778 -1.8796) (xy 1.778 -1.8796) (xy 1.778 1.8796)
			)
			(stroke
				(width 0)
				(type default)
			)
			(fill no)
			(layer "F.CrtYd")
		)
		(fp_poly
			(pts
				(xy -1.778 1.8796) (xy -1.778 -1.8796) (xy 1.778 -1.8796) (xy 1.778 1.8796)
			)
			(stroke
				(width 0)
				(type default)
			)
			(fill no)
			(layer "F.Fab")
		)
		(pad "D" smd custom
			(at 0 -0.9525)
			(size 0.1905 0.1905)
			(layers "F.Cu" "F.Mask" "F.Paste")
			(net "FLT_HDD31_N")
			(options
				(clearance outline)
				(anchor circle)
			)
			(primitives
				(gr_poly
					(pts
						(arc
							(start -0.1778 0.5715)
							(mid -0.321484 0.511984)
							(end -0.381 0.3683)
						)
						(arc
							(start -0.381 -0.3683)
							(mid -0.321484 -0.511984)
							(end -0.1778 -0.5715)
						)
						(arc
							(start 0.1778 -0.5715)
							(mid 0.321484 -0.511984)
							(end 0.381 -0.3683)
						)
						(arc
							(start 0.381 0.3683)
							(mid 0.321484 0.511984)
							(end 0.1778 0.5715)
						)
					)
					(width 0)
					(fill yes)
				)
			)
		)
		(pad "G" smd custom
			(at -0.98425 0.9525)
			(size 0.1905 0.1905)
			(layers "F.Cu" "F.Mask" "F.Paste")
			(net "DRIVE_B_31_FLT_LED")
			(options
				(clearance outline)
				(anchor circle)
			)
			(primitives
				(gr_poly
					(pts
						(arc
							(start -0.1778 0.5715)
							(mid -0.321484 0.511984)
							(end -0.381 0.3683)
						)
						(arc
							(start -0.381 -0.3683)
							(mid -0.321484 -0.511984)
							(end -0.1778 -0.5715)
						)
						(arc
							(start 0.1778 -0.5715)
							(mid 0.321484 -0.511984)
							(end 0.381 -0.3683)
						)
						(arc
							(start 0.381 0.3683)
							(mid 0.321484 0.511984)
							(end 0.1778 0.5715)
						)
					)
					(width 0)
					(fill yes)
				)
			)
		)
		(pad "S" smd custom
			(at 0.98425 0.9525)
			(size 0.1905 0.1905)
			(layers "F.Cu" "F.Mask" "F.Paste")
			(net "GND")
			(options
				(clearance outline)
				(anchor circle)
			)
			(primitives
				(gr_poly
					(pts
						(arc
							(start -0.1778 0.5715)
							(mid -0.321484 0.511984)
							(end -0.381 0.3683)
						)
						(arc
							(start -0.381 -0.3683)
							(mid -0.321484 -0.511984)
							(end -0.1778 -0.5715)
						)
						(arc
							(start 0.1778 -0.5715)
							(mid 0.321484 -0.511984)
							(end 0.381 -0.3683)
						)
						(arc
							(start 0.381 0.3683)
							(mid 0.321484 0.511984)
							(end 0.1778 0.5715)
						)
					)
					(width 0)
					(fill yes)
				)
			)
		)
	)
	(footprint ""
		(layer "F.Cu")
		(at 16.824198 -282.110942 90)
		(property "Reference" "R965"
			(at 0 0 90)
			(layer "F.SilkS")
			(hide yes)
			(effects
				(font
					(size 1.27 1.27)
				)
			)
		)
		(property "Value" "4K7R2J-2-GP"
			(at 0.064008 -3.993896 90)
			(unlocked yes)
			(layer "F.Fab")
			(hide yes)
			(effects
				(font
					(size 1.016 1.016)
					(thickness 0.1524)
				)
			)
		)
		(property "Device Type" "R402H16"
			(at 0.064008 -5.517896 90)
			(unlocked yes)
			(layer "F.Fab")
			(hide yes)
			(effects
				(font
					(size 1.016 1.016)
					(thickness 0.1524)
				)
			)
		)
		(duplicate_pad_numbers_are_jumpers no)
		(fp_line
			(start 0.508 -0.9398)
			(end -0.508 -0.9398)
			(stroke
				(width 0.1524)
				(type default)
			)
			(layer "F.SilkS")
		)
		(fp_line
			(start -0.508 -0.9398)
			(end -0.508 0.9398)
			(stroke
				(width 0.1524)
				(type default)
			)
			(layer "F.SilkS")
		)
		(fp_rect
			(start -0.508 0.9398)
			(end 0.508 -0.9398)
			(stroke
				(width 0)
				(type default)
			)
			(fill no)
			(layer "F.CrtYd")
		)
		(fp_rect
			(start -0.508 0.9398)
			(end 0.508 -0.9398)
			(stroke
				(width 0)
				(type default)
			)
			(fill no)
			(layer "F.Fab")
		)
		(pad "1" smd custom
			(at 0 -0.4445 90)
			(size 0.1397 0.1397)
			(layers "F.Cu" "F.Mask" "F.Paste")
			(net "P12V_A")
			(options
				(clearance outline)
				(anchor circle)
			)
			(primitives
				(gr_poly
					(pts
						(arc
							(start -0.1778 -0.2794)
							(mid -0.249642 -0.249642)
							(end -0.2794 -0.1778)
						)
						(arc
							(start -0.2794 0.1778)
							(mid -0.249642 0.249642)
							(end -0.1778 0.2794)
						)
						(arc
							(start 0.1778 0.2794)
							(mid 0.249642 0.249642)
							(end 0.2794 0.1778)
						)
						(arc
							(start 0.2794 -0.1778)
							(mid 0.249642 -0.249642)
							(end 0.1778 -0.2794)
						)
					)
					(width 0)
					(fill yes)
				)
			)
		)
		(pad "2" smd custom
			(at 0 0.4445 90)
			(size 0.1397 0.1397)
			(layers "F.Cu" "F.Mask" "F.Paste")
			(net "SW_HDD_P0")
			(options
				(clearance outline)
				(anchor circle)
			)
			(primitives
				(gr_poly
					(pts
						(arc
							(start -0.1778 -0.2794)
							(mid -0.249642 -0.249642)
							(end -0.2794 -0.1778)
						)
						(arc
							(start -0.2794 0.1778)
							(mid -0.249642 0.249642)
							(end -0.1778 0.2794)
						)
						(arc
							(start 0.1778 0.2794)
							(mid 0.249642 0.249642)
							(end 0.2794 0.1778)
						)
						(arc
							(start 0.2794 -0.1778)
							(mid 0.249642 -0.249642)
							(end 0.1778 -0.2794)
						)
					)
					(width 0)
					(fill yes)
				)
			)
		)
	)
	(footprint ""
		(layer "F.Cu")
		(at 267.00099 -147.408138 90)
		(property "Reference" "TP188"
			(at 0 0 90)
			(layer "F.SilkS")
			(hide yes)
			(effects
				(font
					(size 1.27 1.27)
				)
			)
		)
		(property "Value" "TPAD32-GP"
			(at -0.0508 -1.6764 90)
			(unlocked yes)
			(layer "F.Fab")
			(hide yes)
			(effects
				(font
					(size 1.016 1.016)
					(thickness 0.1524)
				)
			)
		)
		(property "Device Type" "TPAD32"
			(at -0.0508 -3.2004 90)
			(unlocked yes)
			(layer "F.Fab")
			(hide yes)
			(effects
				(font
					(size 1.016 1.016)
					(thickness 0.1524)
				)
			)
		)
		(duplicate_pad_numbers_are_jumpers no)
		(fp_poly
			(pts
				(arc
					(start 0 0.4064)
					(mid 0 -0.4064)
					(end 0 0.4064)
				)
			)
			(stroke
				(width 0)
				(type default)
			)
			(fill no)
			(layer "F.CrtYd")
		)
		(fp_poly
			(pts
				(arc
					(start 0 0.7112)
					(mid 0 -0.7112)
					(end 0 0.7112)
				)
			)
			(stroke
				(width 0)
				(type default)
			)
			(fill no)
			(layer "F.Fab")
		)
		(pad "1" smd circle
			(at 0 0 90)
			(size 0.8128 0.8128)
			(layers "F.Cu" "F.Mask" "F.Paste")
			(net "TP_COMP_B_KR_P0_RX_DN")
		)
	)
)
